(kicad_pcb
	(version 20260206)
	(generator "pcbnew")
	(generator_version "10.0")
	(general
		(thickness 1.6)
		(legacy_teardrops no)
	)
	(paper "A4")
	(title_block
		(title "baseboard — 13948-1b.1110WZS1818.brd")
		(comment 1 "Honey Badger (Wiwynn) / footprints 1519-1525 of 2523")
	)
	(layers
		(0 "F.Cu" signal "TOP")
		(4 "In1.Cu" signal "L2GND")
		(6 "In2.Cu" signal "L3")
		(8 "In3.Cu" signal "L4VCC")
		(10 "In4.Cu" signal "L5VCC")
		(12 "In5.Cu" signal "L6")
		(14 "In6.Cu" signal "L7GND")
		(2 "B.Cu" signal "BOTTOM")
		(9 "F.Adhes" user "F.Adhesive")
		(11 "B.Adhes" user "B.Adhesive")
		(13 "F.Paste" user "Package Geometry/Pastemask Top")
		(15 "B.Paste" user "Package Geometry/Pastemask Bottom")
		(5 "F.SilkS" user "Ref Des/Silkscreen Top")
		(7 "B.SilkS" user "Ref Des/Silkscreen Bottom")
		(1 "F.Mask" user "Board Geometry/Soldermask Top")
		(3 "B.Mask" user "Board Geometry/Soldermask Bottom")
		(17 "Dwgs.User" user "User.Drawings")
		(19 "Cmts.User" user "User.Comments")
		(21 "Eco1.User" user "User.Eco1")
		(23 "Eco2.User" user "User.Eco2")
		(25 "Edge.Cuts" user "Board Geometry/Outline")
		(27 "Margin" user)
		(31 "F.CrtYd" user "Package Geometry/Place Bound Top")
		(29 "B.CrtYd" user "Package Geometry/Place Bound Bottom")
		(35 "F.Fab" user "Ref Des/Assembly Top")
		(33 "B.Fab" user "Ref Des/Assembly Bottom")
	)
	(footprint ""
		(layer "F.Cu")
		(at 208.534 -93.599 -90)
		(property "Reference" "PC146"
			(at 0 0 270)
			(layer "F.SilkS")
			(hide yes)
			(effects
				(font
					(size 1.27 1.27)
				)
			)
		)
		(property "Value" "SCD1U10V2KX-5GP"
			(at 1.1811 -2.7051 270)
			(unlocked yes)
			(layer "F.Fab")
			(hide yes)
			(effects
				(font
					(size 1.016 1.016)
					(thickness 0.1524)
				)
			)
		)
		(property "Device Type" "C402H22"
			(at 1.1811 -4.2291 270)
			(unlocked yes)
			(layer "F.Fab")
			(hide yes)
			(effects
				(font
					(size 1.016 1.016)
					(thickness 0.1524)
				)
			)
		)
		(duplicate_pad_numbers_are_jumpers no)
		(fp_rect
			(start -0.4318 0.9525)
			(end 0.4318 -0.9525)
			(stroke
				(width 0)
				(type default)
			)
			(fill no)
			(layer "F.CrtYd")
		)
		(fp_rect
			(start -0.4318 0.9525)
			(end 0.4318 -0.9525)
			(stroke
				(width 0)
				(type default)
			)
			(fill no)
			(layer "F.Fab")
		)
		(pad "1" smd custom
			(at 0 -0.4445 270)
			(size 0.1524 0.1524)
			(layers "F.Cu" "F.Mask" "F.Paste")
			(net "P1V5_C")
			(options
				(clearance outline)
				(anchor circle)
			)
			(primitives
				(gr_poly
					(pts
						(arc
							(start 0.3048 -0.2032)
							(mid 0.275042 -0.275042)
							(end 0.2032 -0.3048)
						)
						(arc
							(start -0.2032 -0.3048)
							(mid -0.275042 -0.275042)
							(end -0.3048 -0.2032)
						)
						(arc
							(start -0.3048 0.2032)
							(mid -0.275042 0.275042)
							(end -0.2032 0.3048)
						)
						(arc
							(start 0.2032 0.3048)
							(mid 0.275042 0.275042)
							(end 0.3048 0.2032)
						)
					)
					(width 0)
					(fill yes)
				)
			)
		)
		(pad "2" smd custom
			(at 0 0.4445 270)
			(size 0.1524 0.1524)
			(layers "F.Cu" "F.Mask" "F.Paste")
			(net "GND")
			(options
				(clearance outline)
				(anchor circle)
			)
			(primitives
				(gr_poly
					(pts
						(arc
							(start 0.3048 -0.2032)
							(mid 0.275042 -0.275042)
							(end 0.2032 -0.3048)
						)
						(arc
							(start -0.2032 -0.3048)
							(mid -0.275042 -0.275042)
							(end -0.3048 -0.2032)
						)
						(arc
							(start -0.3048 0.2032)
							(mid -0.275042 0.275042)
							(end -0.2032 0.3048)
						)
						(arc
							(start 0.2032 0.3048)
							(mid 0.275042 0.275042)
							(end 0.3048 0.2032)
						)
					)
					(width 0)
					(fill yes)
				)
			)
		)
	)
	(footprint ""
		(layer "F.Cu")
		(at 95.89897 -88.519 -90)
		(property "Reference" "SR787"
			(at 0 0 270)
			(layer "F.SilkS")
			(hide yes)
			(effects
				(font
					(size 1.27 1.27)
				)
			)
		)
		(property "Value" "4K75R2F-1-GP"
			(at 0.064008 -3.993896 270)
			(unlocked yes)
			(layer "F.Fab")
			(hide yes)
			(effects
				(font
					(size 1.016 1.016)
					(thickness 0.1524)
				)
			)
		)
		(property "Device Type" "R402H16"
			(at 0.064008 -5.517896 270)
			(unlocked yes)
			(layer "F.Fab")
			(hide yes)
			(effects
				(font
					(size 1.016 1.016)
					(thickness 0.1524)
				)
			)
		)
		(duplicate_pad_numbers_are_jumpers no)
		(fp_line
			(start -0.508 -0.9398)
			(end -0.508 0.9398)
			(stroke
				(width 0.1524)
				(type default)
			)
			(layer "F.SilkS")
		)
		(fp_line
			(start 0.508 -0.9398)
			(end -0.508 -0.9398)
			(stroke
				(width 0.1524)
				(type default)
			)
			(layer "F.SilkS")
		)
		(fp_rect
			(start -0.508 0.9398)
			(end 0.508 -0.9398)
			(stroke
				(width 0)
				(type default)
			)
			(fill no)
			(layer "F.CrtYd")
		)
		(fp_rect
			(start -0.508 0.9398)
			(end 0.508 -0.9398)
			(stroke
				(width 0)
				(type default)
			)
			(fill no)
			(layer "F.Fab")
		)
		(pad "1" smd custom
			(at 0 -0.4445 270)
			(size 0.1397 0.1397)
			(layers "F.Cu" "F.Mask" "F.Paste")
			(net "EXP_CPU_MODE_0")
			(options
				(clearance outline)
				(anchor circle)
			)
			(primitives
				(gr_poly
					(pts
						(arc
							(start -0.1778 -0.2794)
							(mid -0.249642 -0.249642)
							(end -0.2794 -0.1778)
						)
						(arc
							(start -0.2794 0.1778)
							(mid -0.249642 0.249642)
							(end -0.1778 0.2794)
						)
						(arc
							(start 0.1778 0.2794)
							(mid 0.249642 0.249642)
							(end 0.2794 0.1778)
						)
						(arc
							(start 0.2794 -0.1778)
							(mid 0.249642 -0.249642)
							(end 0.1778 -0.2794)
						)
					)
					(width 0)
					(fill yes)
				)
			)
		)
		(pad "2" smd custom
			(at 0 0.4445 270)
			(size 0.1397 0.1397)
			(layers "F.Cu" "F.Mask" "F.Paste")
			(net "GND")
			(options
				(clearance outline)
				(anchor circle)
			)
			(primitives
				(gr_poly
					(pts
						(arc
							(start -0.1778 -0.2794)
							(mid -0.249642 -0.249642)
							(end -0.2794 -0.1778)
						)
						(arc
							(start -0.2794 0.1778)
							(mid -0.249642 0.249642)
							(end -0.1778 0.2794)
						)
						(arc
							(start 0.1778 0.2794)
							(mid 0.249642 0.249642)
							(end 0.2794 0.1778)
						)
						(arc
							(start 0.2794 -0.1778)
							(mid 0.249642 -0.249642)
							(end 0.1778 -0.2794)
						)
					)
					(width 0)
					(fill yes)
				)
			)
		)
	)
	(footprint ""
		(layer "F.Cu")
		(at 314.706 -185.293 90)
		(property "Reference" "R311"
			(at 0 0 90)
			(layer "F.SilkS")
			(hide yes)
			(effects
				(font
					(size 1.27 1.27)
				)
			)
		)
		(property "Value" "0R2J-2-GP"
			(at 0.064008 -3.993896 90)
			(unlocked yes)
			(layer "F.Fab")
			(hide yes)
			(effects
				(font
					(size 1.016 1.016)
					(thickness 0.1524)
				)
			)
		)
		(property "Device Type" "R402H16"
			(at 0.064008 -5.517896 90)
			(unlocked yes)
			(layer "F.Fab")
			(hide yes)
			(effects
				(font
					(size 1.016 1.016)
					(thickness 0.1524)
				)
			)
		)
		(duplicate_pad_numbers_are_jumpers no)
		(fp_line
			(start 0.508 -0.9398)
			(end -0.508 -0.9398)
			(stroke
				(width 0.1524)
				(type default)
			)
			(layer "F.SilkS")
		)
		(fp_line
			(start -0.508 -0.9398)
			(end -0.508 0.9398)
			(stroke
				(width 0.1524)
				(type default)
			)
			(layer "F.SilkS")
		)
		(fp_rect
			(start -0.508 0.9398)
			(end 0.508 -0.9398)
			(stroke
				(width 0)
				(type default)
			)
			(fill no)
			(layer "F.CrtYd")
		)
		(fp_rect
			(start -0.508 0.9398)
			(end 0.508 -0.9398)
			(stroke
				(width 0)
				(type default)
			)
			(fill no)
			(layer "F.Fab")
		)
		(pad "1" smd custom
			(at 0 -0.4445 90)
			(size 0.1397 0.1397)
			(layers "F.Cu" "F.Mask" "F.Paste")
			(net "BMC0_LED_DR_R_LED0")
			(options
				(clearance outline)
				(anchor circle)
			)
			(primitives
				(gr_poly
					(pts
						(arc
							(start -0.1778 -0.2794)
							(mid -0.249642 -0.249642)
							(end -0.2794 -0.1778)
						)
						(arc
							(start -0.2794 0.1778)
							(mid -0.249642 0.249642)
							(end -0.1778 0.2794)
						)
						(arc
							(start 0.1778 0.2794)
							(mid 0.249642 0.249642)
							(end 0.2794 0.1778)
						)
						(arc
							(start 0.2794 -0.1778)
							(mid 0.249642 -0.249642)
							(end 0.1778 -0.2794)
						)
					)
					(width 0)
					(fill yes)
				)
			)
		)
		(pad "2" smd custom
			(at 0 0.4445 90)
			(size 0.1397 0.1397)
			(layers "F.Cu" "F.Mask" "F.Paste")
			(net "LED_DR_LED0")
			(options
				(clearance outline)
				(anchor circle)
			)
			(primitives
				(gr_poly
					(pts
						(arc
							(start -0.1778 -0.2794)
							(mid -0.249642 -0.249642)
							(end -0.2794 -0.1778)
						)
						(arc
							(start -0.2794 0.1778)
							(mid -0.249642 0.249642)
							(end -0.1778 0.2794)
						)
						(arc
							(start 0.1778 0.2794)
							(mid 0.249642 0.249642)
							(end 0.2794 0.1778)
						)
						(arc
							(start 0.2794 -0.1778)
							(mid 0.249642 -0.249642)
							(end 0.1778 -0.2794)
						)
					)
					(width 0)
					(fill yes)
				)
			)
		)
	)
	(footprint ""
		(layer "F.Cu")
		(at 325.374 -182.372 180)
		(property "Reference" "R5765"
			(at 0 0 180)
			(layer "F.SilkS")
			(hide yes)
			(effects
				(font
					(size 1.27 1.27)
				)
			)
		)
		(property "Value" "1K8R2F-GP"
			(at 0.064008 -3.993896 180)
			(unlocked yes)
			(layer "F.Fab")
			(hide yes)
			(effects
				(font
					(size 1.016 1.016)
					(thickness 0.1524)
				)
			)
		)
		(property "Device Type" "R402H16"
			(at 0.064008 -5.517896 180)
			(unlocked yes)
			(layer "F.Fab")
			(hide yes)
			(effects
				(font
					(size 1.016 1.016)
					(thickness 0.1524)
				)
			)
		)
		(duplicate_pad_numbers_are_jumpers no)
		(fp_line
			(start 0.508 -0.9398)
			(end -0.508 -0.9398)
			(stroke
				(width 0.1524)
				(type default)
			)
			(layer "F.SilkS")
		)
		(fp_line
			(start -0.508 -0.9398)
			(end -0.508 0.9398)
			(stroke
				(width 0.1524)
				(type default)
			)
			(layer "F.SilkS")
		)
		(fp_rect
			(start -0.508 0.9398)
			(end 0.508 -0.9398)
			(stroke
				(width 0)
				(type default)
			)
			(fill no)
			(layer "F.CrtYd")
		)
		(fp_rect
			(start -0.508 0.9398)
			(end 0.508 -0.9398)
			(stroke
				(width 0)
				(type default)
			)
			(fill no)
			(layer "F.Fab")
		)
		(pad "1" smd custom
			(at 0 -0.4445 180)
			(size 0.1397 0.1397)
			(layers "F.Cu" "F.Mask" "F.Paste")
			(net "P1V8_STBY")
			(options
				(clearance outline)
				(anchor circle)
			)
			(primitives
				(gr_poly
					(pts
						(arc
							(start -0.1778 -0.2794)
							(mid -0.249642 -0.249642)
							(end -0.2794 -0.1778)
						)
						(arc
							(start -0.2794 0.1778)
							(mid -0.249642 0.249642)
							(end -0.1778 0.2794)
						)
						(arc
							(start 0.1778 0.2794)
							(mid 0.249642 0.249642)
							(end 0.2794 0.1778)
						)
						(arc
							(start 0.2794 -0.1778)
							(mid 0.249642 -0.249642)
							(end 0.1778 -0.2794)
						)
					)
					(width 0)
					(fill yes)
				)
			)
		)
		(pad "2" smd custom
			(at 0 0.4445 180)
			(size 0.1397 0.1397)
			(layers "F.Cu" "F.Mask" "F.Paste")
			(net "ADC_P1V8_STBY")
			(options
				(clearance outline)
				(anchor circle)
			)
			(primitives
				(gr_poly
					(pts
						(arc
							(start -0.1778 -0.2794)
							(mid -0.249642 -0.249642)
							(end -0.2794 -0.1778)
						)
						(arc
							(start -0.2794 0.1778)
							(mid -0.249642 0.249642)
							(end -0.1778 0.2794)
						)
						(arc
							(start 0.1778 0.2794)
							(mid 0.249642 0.249642)
							(end 0.2794 0.1778)
						)
						(arc
							(start 0.2794 -0.1778)
							(mid 0.249642 -0.249642)
							(end 0.1778 -0.2794)
						)
					)
					(width 0)
					(fill yes)
				)
			)
		)
	)
	(footprint ""
		(layer "F.Cu")
		(at 86.0806 -3.683)
		(property "Reference" "PC202"
			(at 0 0 0)
			(layer "F.SilkS")
			(hide yes)
			(effects
				(font
					(size 1.27 1.27)
				)
			)
		)
		(property "Value" "SC22U6D3V6KX-2-GP"
			(at -0.0762 -5.1308 0)
			(unlocked yes)
			(layer "F.Fab")
			(hide yes)
			(effects
				(font
					(size 1.016 1.016)
					(thickness 0.1524)
				)
			)
		)
		(property "Device Type" "C1206H71"
			(at -0.127 -6.6548 0)
			(unlocked yes)
			(layer "F.Fab")
			(hide yes)
			(effects
				(font
					(size 1.016 1.016)
					(thickness 0.1524)
				)
			)
		)
		(duplicate_pad_numbers_are_jumpers no)
		(fp_line
			(start -1.016 -2.2352)
			(end 1.016 -2.2352)
			(stroke
				(width 0.1524)
				(type default)
			)
			(layer "F.SilkS")
		)
		(fp_line
			(start -1.016 -0.8382)
			(end -1.016 -2.2352)
			(stroke
				(width 0.1524)
				(type default)
			)
			(layer "F.SilkS")
		)
		(fp_line
			(start -1.016 2.2352)
			(end -1.016 0.8382)
			(stroke
				(width 0.1524)
				(type default)
			)
			(layer "F.SilkS")
		)
		(fp_line
			(start 1.016 -2.2352)
			(end 1.016 -0.8382)
			(stroke
				(width 0.1524)
				(type default)
			)
			(layer "F.SilkS")
		)
		(fp_line
			(start 1.016 0.8382)
			(end 1.016 2.2352)
			(stroke
				(width 0.1524)
				(type default)
			)
			(layer "F.SilkS")
		)
		(fp_line
			(start 1.016 2.2352)
			(end -1.016 2.2352)
			(stroke
				(width 0.1524)
				(type default)
			)
			(layer "F.SilkS")
		)
		(fp_rect
			(start -1.0922 2.3114)
			(end 1.0922 -2.3114)
			(stroke
				(width 0)
				(type default)
			)
			(fill no)
			(layer "F.CrtYd")
		)
		(fp_poly
			(pts
				(xy 1.0922 -2.3114) (xy 1.0922 2.3114) (xy -1.0922 2.3114) (xy -1.0922 -2.3114)
			)
			(stroke
				(width 0)
				(type default)
			)
			(fill no)
			(layer "F.Fab")
		)
		(pad "1" smd rect
			(at 0 -1.397)
			(size 1.651 1.27)
			(layers "F.Cu" "F.Mask" "F.Paste")
			(net "P0V955_C")
		)
		(pad "2" smd rect
			(at 0 1.397)
			(size 1.651 1.27)
			(layers "F.Cu" "F.Mask" "F.Paste")
			(net "GND")
		)
	)
	(footprint ""
		(layer "F.Cu")
		(at 45.98797 -144.653)
		(property "Reference" "SU75"
			(at 0 0 0)
			(layer "F.SilkS")
			(hide yes)
			(effects
				(font
					(size 1.27 1.27)
				)
			)
		)
		(property "Value" "TPS3808G18DRVT-GP-U"
			(at -2.7813 -0.4572 0)
			(unlocked yes)
			(layer "F.Fab")
			(hide yes)
			(effects
				(font
					(size 1.016 1.016)
					(thickness 0.1524)
				)
			)
		)
		(property "Device Type" "DFN6F2-G1711-UH32"
			(at -2.7813 -1.9812 0)
			(unlocked yes)
			(layer "F.Fab")
			(hide yes)
			(effects
				(font
					(size 1.016 1.016)
					(thickness 0.1524)
				)
			)
		)
		(duplicate_pad_numbers_are_jumpers no)
		(fp_line
			(start -1.5113 -1.7653)
			(end -0.7493 -1.7653)
			(stroke
				(width 0.1524)
				(type default)
			)
			(layer "F.SilkS")
		)
		(fp_line
			(start -1.5113 -1.0033)
			(end -1.5113 -1.7653)
			(stroke
				(width 0.1524)
				(type default)
			)
			(layer "F.SilkS")
		)
		(fp_line
			(start -1.5113 1.0033)
			(end -1.5113 1.7653)
			(stroke
				(width 0.1524)
				(type default)
			)
			(layer "F.SilkS")
		)
		(fp_line
			(start -1.5113 1.7653)
			(end -0.7493 1.7653)
			(stroke
				(width 0.1524)
				(type default)
			)
			(layer "F.SilkS")
		)
		(fp_line
			(start 0 1.5113)
			(end 0 2.0193)
			(stroke
				(width 0.1524)
				(type default)
			)
			(layer "F.SilkS")
		)
		(fp_line
			(start 1.5113 1.0033)
			(end 1.5113 1.7653)
			(stroke
				(width 0.1524)
				(type default)
			)
			(layer "F.SilkS")
		)
		(fp_line
			(start 1.5113 1.7653)
			(end 0.7493 1.7653)
			(stroke
				(width 0.1524)
				(type default)
			)
			(layer "F.SilkS")
		)
		(fp_poly
			(pts
				(xy 0.7493 -1.7653) (xy 1.5113 -1.0033) (xy 1.5113 -1.7653)
			)
			(stroke
				(width 0)
				(type default)
			)
			(fill yes)
			(layer "F.SilkS")
		)
		(fp_rect
			(start -1.0033 1.0033)
			(end 1.0033 -1.0033)
			(stroke
				(width 0)
				(type default)
			)
			(fill no)
			(layer "F.CrtYd")
		)
		(fp_poly
			(pts
				(xy -1.5113 1.7653) (xy -1.5113 -1.7653) (xy 1.5113 -1.7653) (xy 1.5113 0.99822) (xy 1.0033 0.99822)
				(xy 1.0033 -1.0033) (xy -1.0033 -1.0033) (xy -1.0033 1.0033) (xy 1.5113 1.0033) (xy 1.5113 1.7653)
			)
			(stroke
				(width 0)
				(type default)
			)
			(fill no)
			(layer "F.CrtYd")
		)
		(fp_rect
			(start -1.5113 1.7653)
			(end 1.5113 -1.7653)
			(stroke
				(width 0)
				(type default)
			)
			(fill no)
			(layer "F.Fab")
		)
		(pad "1" smd rect
			(at 0.649986 -1.1303)
			(size 0.4064 0.508)
			(drill
				(offset 0 0.127)
			)
			(layers "F.Cu" "F.Mask" "F.Paste")
			(net "P1V8_STBY")
		)
		(pad "2" smd rect
			(at 0 -1.1303)
			(size 0.4064 0.508)
			(drill
				(offset 0 0.127)
			)
			(layers "F.Cu" "F.Mask" "F.Paste")
			(net "P1V8_STBY")
		)
		(pad "3" smd rect
			(at -0.649986 -1.1303)
			(size 0.4064 0.508)
			(drill
				(offset 0 0.127)
			)
			(layers "F.Cu" "F.Mask" "F.Paste")
			(net "Net_7")
		)
		(pad "4" smd rect
			(at -0.649986 1.1303)
			(size 0.4064 0.508)
			(drill
				(offset 0 -0.127)
			)
			(layers "F.Cu" "F.Mask" "F.Paste")
			(net "EXP_RESET_MR_N")
		)
		(pad "5" smd rect
			(at 0 1.1303)
			(size 0.4064 0.508)
			(drill
				(offset 0 -0.127)
			)
			(layers "F.Cu" "F.Mask" "F.Paste")
			(net "GND")
		)
		(pad "6" smd rect
			(at 0.649986 1.1303)
			(size 0.4064 0.508)
			(drill
				(offset 0 -0.127)
			)
			(layers "F.Cu" "F.Mask" "F.Paste")
			(net "EXP_RESET_N")
		)
		(pad "7" smd rect
			(at 0 0)
			(size 1.7018 1.0922)
			(layers "F.Cu" "F.Mask" "F.Paste")
			(net "GND")
		)
	)
	(footprint ""
		(layer "F.Cu")
		(at 96.647 -99.822)
		(property "Reference" "STP81"
			(at 0 0 0)
			(layer "F.SilkS")
			(hide yes)
			(effects
				(font
					(size 1.27 1.27)
				)
			)
		)
		(property "Value" "TPAD28"
			(at 0.0127 -1.8034 0)
			(unlocked yes)
			(layer "F.Fab")
			(hide yes)
			(effects
				(font
					(size 1.016 1.016)
					(thickness 0.1524)
				)
			)
		)
		(property "Device Type" "TPAD28"
			(at 0.0127 -3.3274 0)
			(unlocked yes)
			(layer "F.Fab")
			(hide yes)
			(effects
				(font
					(size 1.016 1.016)
					(thickness 0.1524)
				)
			)
		)
		(duplicate_pad_numbers_are_jumpers no)
		(fp_poly
			(pts
				(arc
					(start 0.3556 0)
					(mid -0.3556 0)
					(end 0.3556 0)
				)
			)
			(stroke
				(width 0)
				(type default)
			)
			(fill no)
			(layer "F.CrtYd")
		)
		(fp_poly
			(pts
				(arc
					(start 0.6096 0)
					(mid -0.6096 0)
					(end 0.6096 0)
				)
			)
			(stroke
				(width 0)
				(type default)
			)
			(fill no)
			(layer "F.Fab")
		)
		(pad "1" smd circle
			(at 0 0)
			(size 0.7112 0.7112)
			(layers "F.Cu" "F.Mask" "F.Paste")
			(net "EXP_TACH_IN1")
		)
	)
)
